(kicad_pcb
	(version 20260206)
	(generator "pcbnew")
	(generator_version "10.0")
	(general
		(thickness 1.6)
		(legacy_teardrops no)
	)
	(paper "A4")
	(title_block
		(title "Bryce Canyon_F.DPB_16315-1-OCP.brd")
		(comment 1 "Bryce Canyon / footprints 1432-1439 of 2223")
	)
	(layers
		(0 "F.Cu" signal "TOP")
		(4 "In1.Cu" signal "L2GND")
		(6 "In2.Cu" signal "L3")
		(8 "In3.Cu" signal "L4GND")
		(10 "In4.Cu" signal "L5")
		(12 "In5.Cu" signal "L6VCC")
		(14 "In6.Cu" signal "L7VCC")
		(16 "In7.Cu" signal "L8")
		(18 "In8.Cu" signal "L9GND")
		(20 "In9.Cu" signal "L10")
		(22 "In10.Cu" signal "L11GND")
		(2 "B.Cu" signal "BOTTOM")
		(9 "F.Adhes" user "F.Adhesive")
		(11 "B.Adhes" user "B.Adhesive")
		(13 "F.Paste" user "Package Geometry/Pastemask Top")
		(15 "B.Paste" user "Package Geometry/Pastemask Bottom")
		(5 "F.SilkS" user "Ref Des/Silkscreen Top")
		(7 "B.SilkS" user "Ref Des/Silkscreen Bottom")
		(1 "F.Mask" user "Board Geometry/Soldermask Top")
		(3 "B.Mask" user "Board Geometry/Soldermask Bottom")
		(17 "Dwgs.User" user "User.Drawings")
		(19 "Cmts.User" user "User.Comments")
		(21 "Eco1.User" user "User.Eco1")
		(23 "Eco2.User" user "User.Eco2")
		(25 "Edge.Cuts" user "Board Geometry/Outline")
		(27 "Margin" user)
		(31 "F.CrtYd" user "Package Geometry/Place Bound Top")
		(29 "B.CrtYd" user "Package Geometry/Place Bound Bottom")
		(35 "F.Fab" user "Ref Des/Assembly Top")
		(33 "B.Fab" user "Ref Des/Assembly Bottom")
	)
	(footprint ""
		(layer "F.Cu")
		(at 80.724248 -26.804874)
		(property "Reference" "C12"
			(at 0 0 0)
			(layer "F.SilkS")
			(hide yes)
			(effects
				(font
					(size 1.27 1.27)
				)
			)
		)
		(property "Value" "SCD1U16V2KX-3GP"
			(at 1.1811 -2.7051 0)
			(unlocked yes)
			(layer "F.Fab")
			(hide yes)
			(effects
				(font
					(size 1.016 1.016)
					(thickness 0.1524)
				)
			)
		)
		(property "Device Type" "C402H22"
			(at 1.1811 -4.2291 0)
			(unlocked yes)
			(layer "F.Fab")
			(hide yes)
			(effects
				(font
					(size 1.016 1.016)
					(thickness 0.1524)
				)
			)
		)
		(duplicate_pad_numbers_are_jumpers no)
		(fp_rect
			(start -0.4318 0.9525)
			(end 0.4318 -0.9525)
			(stroke
				(width 0)
				(type default)
			)
			(fill no)
			(layer "F.CrtYd")
		)
		(fp_rect
			(start -0.4318 0.9525)
			(end 0.4318 -0.9525)
			(stroke
				(width 0)
				(type default)
			)
			(fill no)
			(layer "F.Fab")
		)
		(pad "1" smd custom
			(at 0 -0.4445)
			(size 0.1524 0.1524)
			(layers "F.Cu" "F.Mask" "F.Paste")
			(net "P3V3_STBY_A")
			(options
				(clearance outline)
				(anchor circle)
			)
			(primitives
				(gr_poly
					(pts
						(arc
							(start 0.3048 -0.2032)
							(mid 0.275042 -0.275042)
							(end 0.2032 -0.3048)
						)
						(arc
							(start -0.2032 -0.3048)
							(mid -0.275042 -0.275042)
							(end -0.3048 -0.2032)
						)
						(arc
							(start -0.3048 0.2032)
							(mid -0.275042 0.275042)
							(end -0.2032 0.3048)
						)
						(arc
							(start 0.2032 0.3048)
							(mid 0.275042 0.275042)
							(end 0.3048 0.2032)
						)
					)
					(width 0)
					(fill yes)
				)
			)
		)
		(pad "2" smd custom
			(at 0 0.4445)
			(size 0.1524 0.1524)
			(layers "F.Cu" "F.Mask" "F.Paste")
			(net "GND")
			(options
				(clearance outline)
				(anchor circle)
			)
			(primitives
				(gr_poly
					(pts
						(arc
							(start 0.3048 -0.2032)
							(mid 0.275042 -0.275042)
							(end 0.2032 -0.3048)
						)
						(arc
							(start -0.2032 -0.3048)
							(mid -0.275042 -0.275042)
							(end -0.3048 -0.2032)
						)
						(arc
							(start -0.3048 0.2032)
							(mid -0.275042 0.275042)
							(end -0.2032 0.3048)
						)
						(arc
							(start 0.2032 0.3048)
							(mid 0.275042 0.275042)
							(end 0.3048 0.2032)
						)
					)
					(width 0)
					(fill yes)
				)
			)
		)
	)
	(footprint ""
		(layer "F.Cu")
		(at 370.259102 -172.851318 90)
		(property "Reference" "C296"
			(at 0 0 90)
			(layer "F.SilkS")
			(hide yes)
			(effects
				(font
					(size 1.27 1.27)
				)
			)
		)
		(property "Value" "SCD033U25V2KX-GP"
			(at 1.1811 -2.7051 90)
			(unlocked yes)
			(layer "F.Fab")
			(hide yes)
			(effects
				(font
					(size 1.016 1.016)
					(thickness 0.1524)
				)
			)
		)
		(property "Device Type" "C402H22"
			(at 1.1811 -4.2291 90)
			(unlocked yes)
			(layer "F.Fab")
			(hide yes)
			(effects
				(font
					(size 1.016 1.016)
					(thickness 0.1524)
				)
			)
		)
		(duplicate_pad_numbers_are_jumpers no)
		(fp_rect
			(start -0.4318 0.9525)
			(end 0.4318 -0.9525)
			(stroke
				(width 0)
				(type default)
			)
			(fill no)
			(layer "F.CrtYd")
		)
		(fp_rect
			(start -0.4318 0.9525)
			(end 0.4318 -0.9525)
			(stroke
				(width 0)
				(type default)
			)
			(fill no)
			(layer "F.Fab")
		)
		(pad "1" smd custom
			(at 0 -0.4445 90)
			(size 0.1524 0.1524)
			(layers "F.Cu" "F.Mask" "F.Paste")
			(net "P12V_A")
			(options
				(clearance outline)
				(anchor circle)
			)
			(primitives
				(gr_poly
					(pts
						(arc
							(start 0.3048 -0.2032)
							(mid 0.275042 -0.275042)
							(end 0.2032 -0.3048)
						)
						(arc
							(start -0.2032 -0.3048)
							(mid -0.275042 -0.275042)
							(end -0.3048 -0.2032)
						)
						(arc
							(start -0.3048 0.2032)
							(mid -0.275042 0.275042)
							(end -0.2032 0.3048)
						)
						(arc
							(start 0.2032 0.3048)
							(mid 0.275042 0.275042)
							(end 0.3048 0.2032)
						)
					)
					(width 0)
					(fill yes)
				)
			)
		)
		(pad "2" smd custom
			(at 0 0.4445 90)
			(size 0.1524 0.1524)
			(layers "F.Cu" "F.Mask" "F.Paste")
			(net "SW_HDD_N19")
			(options
				(clearance outline)
				(anchor circle)
			)
			(primitives
				(gr_poly
					(pts
						(arc
							(start 0.3048 -0.2032)
							(mid 0.275042 -0.275042)
							(end 0.2032 -0.3048)
						)
						(arc
							(start -0.2032 -0.3048)
							(mid -0.275042 -0.275042)
							(end -0.3048 -0.2032)
						)
						(arc
							(start -0.3048 0.2032)
							(mid -0.275042 0.275042)
							(end -0.2032 0.3048)
						)
						(arc
							(start 0.2032 0.3048)
							(mid 0.275042 0.275042)
							(end 0.3048 0.2032)
						)
					)
					(width 0)
					(fill yes)
				)
			)
		)
	)
	(footprint ""
		(layer "F.Cu")
		(at 262.258556 -221.676214 90)
		(property "Reference" "R403"
			(at 0 0 90)
			(layer "F.SilkS")
			(hide yes)
			(effects
				(font
					(size 1.27 1.27)
				)
			)
		)
		(property "Value" "1KR2F-3-GP"
			(at 0.064008 -3.993896 90)
			(unlocked yes)
			(layer "F.Fab")
			(hide yes)
			(effects
				(font
					(size 1.016 1.016)
					(thickness 0.1524)
				)
			)
		)
		(property "Device Type" "R402H16"
			(at 0.064008 -5.517896 90)
			(unlocked yes)
			(layer "F.Fab")
			(hide yes)
			(effects
				(font
					(size 1.016 1.016)
					(thickness 0.1524)
				)
			)
		)
		(duplicate_pad_numbers_are_jumpers no)
		(fp_line
			(start 0.508 -0.9398)
			(end -0.508 -0.9398)
			(stroke
				(width 0.1524)
				(type default)
			)
			(layer "F.SilkS")
		)
		(fp_line
			(start -0.508 -0.9398)
			(end -0.508 0.9398)
			(stroke
				(width 0.1524)
				(type default)
			)
			(layer "F.SilkS")
		)
		(fp_rect
			(start -0.508 0.9398)
			(end 0.508 -0.9398)
			(stroke
				(width 0)
				(type default)
			)
			(fill no)
			(layer "F.CrtYd")
		)
		(fp_rect
			(start -0.508 0.9398)
			(end 0.508 -0.9398)
			(stroke
				(width 0)
				(type default)
			)
			(fill no)
			(layer "F.Fab")
		)
		(pad "1" smd custom
			(at 0 -0.4445 90)
			(size 0.1397 0.1397)
			(layers "F.Cu" "F.Mask" "F.Paste")
			(net "P3V3_STBY_A")
			(options
				(clearance outline)
				(anchor circle)
			)
			(primitives
				(gr_poly
					(pts
						(arc
							(start -0.1778 -0.2794)
							(mid -0.249642 -0.249642)
							(end -0.2794 -0.1778)
						)
						(arc
							(start -0.2794 0.1778)
							(mid -0.249642 0.249642)
							(end -0.1778 0.2794)
						)
						(arc
							(start 0.1778 0.2794)
							(mid 0.249642 0.249642)
							(end 0.2794 0.1778)
						)
						(arc
							(start 0.2794 -0.1778)
							(mid 0.249642 -0.249642)
							(end 0.1778 -0.2794)
						)
					)
					(width 0)
					(fill yes)
				)
			)
		)
		(pad "2" smd custom
			(at 0 0.4445 90)
			(size 0.1397 0.1397)
			(layers "F.Cu" "F.Mask" "F.Paste")
			(net "I2C_DPB_A_SDA_BUF")
			(options
				(clearance outline)
				(anchor circle)
			)
			(primitives
				(gr_poly
					(pts
						(arc
							(start -0.1778 -0.2794)
							(mid -0.249642 -0.249642)
							(end -0.2794 -0.1778)
						)
						(arc
							(start -0.2794 0.1778)
							(mid -0.249642 0.249642)
							(end -0.1778 0.2794)
						)
						(arc
							(start 0.1778 0.2794)
							(mid 0.249642 0.249642)
							(end 0.2794 0.1778)
						)
						(arc
							(start 0.2794 -0.1778)
							(mid 0.249642 -0.249642)
							(end 0.1778 -0.2794)
						)
					)
					(width 0)
					(fill yes)
				)
			)
		)
	)
	(footprint ""
		(layer "F.Cu")
		(at 174.5742 -168.152318 -90)
		(property "Reference" "C269"
			(at 0 0 270)
			(layer "F.SilkS")
			(hide yes)
			(effects
				(font
					(size 1.27 1.27)
				)
			)
		)
		(property "Value" "SCD033U25V2KX-GP"
			(at 1.1811 -2.7051 270)
			(unlocked yes)
			(layer "F.Fab")
			(hide yes)
			(effects
				(font
					(size 1.016 1.016)
					(thickness 0.1524)
				)
			)
		)
		(property "Device Type" "C402H22"
			(at 1.1811 -4.2291 270)
			(unlocked yes)
			(layer "F.Fab")
			(hide yes)
			(effects
				(font
					(size 1.016 1.016)
					(thickness 0.1524)
				)
			)
		)
		(duplicate_pad_numbers_are_jumpers no)
		(fp_rect
			(start -0.4318 0.9525)
			(end 0.4318 -0.9525)
			(stroke
				(width 0)
				(type default)
			)
			(fill no)
			(layer "F.CrtYd")
		)
		(fp_rect
			(start -0.4318 0.9525)
			(end 0.4318 -0.9525)
			(stroke
				(width 0)
				(type default)
			)
			(fill no)
			(layer "F.Fab")
		)
		(pad "1" smd custom
			(at 0 -0.4445 270)
			(size 0.1524 0.1524)
			(layers "F.Cu" "F.Mask" "F.Paste")
			(net "SW_HDD_P17")
			(options
				(clearance outline)
				(anchor circle)
			)
			(primitives
				(gr_poly
					(pts
						(arc
							(start 0.3048 -0.2032)
							(mid 0.275042 -0.275042)
							(end 0.2032 -0.3048)
						)
						(arc
							(start -0.2032 -0.3048)
							(mid -0.275042 -0.275042)
							(end -0.3048 -0.2032)
						)
						(arc
							(start -0.3048 0.2032)
							(mid -0.275042 0.275042)
							(end -0.2032 0.3048)
						)
						(arc
							(start 0.2032 0.3048)
							(mid 0.275042 0.275042)
							(end 0.3048 0.2032)
						)
					)
					(width 0)
					(fill yes)
				)
			)
		)
		(pad "2" smd custom
			(at 0 0.4445 270)
			(size 0.1524 0.1524)
			(layers "F.Cu" "F.Mask" "F.Paste")
			(net "GND")
			(options
				(clearance outline)
				(anchor circle)
			)
			(primitives
				(gr_poly
					(pts
						(arc
							(start 0.3048 -0.2032)
							(mid 0.275042 -0.275042)
							(end 0.2032 -0.3048)
						)
						(arc
							(start -0.2032 -0.3048)
							(mid -0.275042 -0.275042)
							(end -0.3048 -0.2032)
						)
						(arc
							(start -0.3048 0.2032)
							(mid -0.275042 0.275042)
							(end -0.2032 0.3048)
						)
						(arc
							(start 0.2032 0.3048)
							(mid 0.275042 0.275042)
							(end 0.3048 0.2032)
						)
					)
					(width 0)
					(fill yes)
				)
			)
		)
	)
	(footprint ""
		(layer "F.Cu")
		(at 456.0189 -296.842942 180)
		(property "Reference" "C170"
			(at 0 0 180)
			(layer "F.SilkS")
			(hide yes)
			(effects
				(font
					(size 1.27 1.27)
				)
			)
		)
		(property "Value" "SC1U16V3KX-5GP"
			(at 0 -2.8194 180)
			(unlocked yes)
			(layer "F.Fab")
			(hide yes)
			(effects
				(font
					(size 1.016 1.016)
					(thickness 0.1524)
				)
			)
		)
		(property "Device Type" "C603H36"
			(at 0 -4.3434 180)
			(unlocked yes)
			(layer "F.Fab")
			(hide yes)
			(effects
				(font
					(size 1.016 1.016)
					(thickness 0.1524)
				)
			)
		)
		(duplicate_pad_numbers_are_jumpers no)
		(fp_line
			(start 0.508 0)
			(end -0.508 0)
			(stroke
				(width 0.2032)
				(type default)
			)
			(layer "F.SilkS")
		)
		(fp_rect
			(start -0.5842 1.3335)
			(end 0.5842 -1.3335)
			(stroke
				(width 0)
				(type default)
			)
			(fill no)
			(layer "F.CrtYd")
		)
		(fp_rect
			(start -0.5842 1.3335)
			(end 0.5842 -1.3335)
			(stroke
				(width 0)
				(type default)
			)
			(fill no)
			(layer "F.Fab")
		)
		(pad "1" smd custom
			(at 0 -0.762 180)
			(size 0.2159 0.2159)
			(layers "F.Cu" "F.Mask" "F.Paste")
			(net "P5V_HDD10")
			(options
				(clearance outline)
				(anchor circle)
			)
			(primitives
				(gr_poly
					(pts
						(arc
							(start -0.3302 -0.4318)
							(mid -0.402042 -0.402042)
							(end -0.4318 -0.3302)
						)
						(arc
							(start -0.4318 0.3302)
							(mid -0.402042 0.402042)
							(end -0.3302 0.4318)
						)
						(arc
							(start 0.3302 0.4318)
							(mid 0.402042 0.402042)
							(end 0.4318 0.3302)
						)
						(arc
							(start 0.4318 -0.3302)
							(mid 0.402042 -0.402042)
							(end 0.3302 -0.4318)
						)
					)
					(width 0)
					(fill yes)
				)
			)
		)
		(pad "2" smd custom
			(at 0 0.762 180)
			(size 0.2159 0.2159)
			(layers "F.Cu" "F.Mask" "F.Paste")
			(net "GND")
			(options
				(clearance outline)
				(anchor circle)
			)
			(primitives
				(gr_poly
					(pts
						(arc
							(start -0.3302 -0.4318)
							(mid -0.402042 -0.402042)
							(end -0.4318 -0.3302)
						)
						(arc
							(start -0.4318 0.3302)
							(mid -0.402042 0.402042)
							(end -0.3302 0.4318)
						)
						(arc
							(start 0.3302 0.4318)
							(mid 0.402042 0.402042)
							(end 0.4318 0.3302)
						)
						(arc
							(start 0.4318 -0.3302)
							(mid 0.402042 -0.402042)
							(end 0.3302 -0.4318)
						)
					)
					(width 0)
					(fill yes)
				)
			)
		)
	)
	(footprint ""
		(layer "F.Cu")
		(at 463.5119 -277.792942 90)
		(property "Reference" "D10"
			(at 0 0 90)
			(layer "F.SilkS")
			(hide yes)
			(effects
				(font
					(size 1.27 1.27)
				)
			)
		)
		(property "Value" "RB551V30-GP"
			(at 0 -6.7818 90)
			(unlocked yes)
			(layer "F.Fab")
			(hide yes)
			(effects
				(font
					(size 1.016 1.016)
					(thickness 0.1524)
				)
			)
		)
		(property "Device Type" "SOD323AKH38"
			(at 0 -8.6868 90)
			(unlocked yes)
			(layer "F.Fab")
			(hide yes)
			(effects
				(font
					(size 1.016 1.016)
					(thickness 0.1524)
				)
			)
		)
		(duplicate_pad_numbers_are_jumpers no)
		(fp_line
			(start 0.889 -1.9304)
			(end 0.889 2.159)
			(stroke
				(width 0.1524)
				(type default)
			)
			(layer "F.SilkS")
		)
		(fp_line
			(start -0.889 -1.9304)
			(end 0.889 -1.9304)
			(stroke
				(width 0.1524)
				(type default)
			)
			(layer "F.SilkS")
		)
		(fp_line
			(start 0.762 2.0574)
			(end -0.762 2.0574)
			(stroke
				(width 0.508)
				(type default)
			)
			(layer "F.SilkS")
		)
		(fp_line
			(start 0.889 2.159)
			(end -0.889 2.159)
			(stroke
				(width 0.1524)
				(type default)
			)
			(layer "F.SilkS")
		)
		(fp_line
			(start -0.889 2.159)
			(end -0.889 -1.9304)
			(stroke
				(width 0.1524)
				(type default)
			)
			(layer "F.SilkS")
		)
		(fp_rect
			(start -1.016 2.3114)
			(end 1.016 -2.0066)
			(stroke
				(width 0)
				(type default)
			)
			(fill no)
			(layer "F.CrtYd")
		)
		(fp_poly
			(pts
				(xy -1.016 -2.0066) (xy 1.016 -2.0066) (xy 1.016 2.3114) (xy -1.016 2.3114)
			)
			(stroke
				(width 0)
				(type default)
			)
			(fill no)
			(layer "F.Fab")
		)
		(pad "A" smd rect
			(at 0 -1.143 90)
			(size 0.5588 1.016)
			(layers "F.Cu" "F.Mask" "F.Paste")
			(net "SW_HDD_R10")
		)
		(pad "K" smd rect
			(at 0 1.143 90)
			(size 0.5588 1.016)
			(layers "F.Cu" "F.Mask" "F.Paste")
			(net "SW_HDD_N10")
		)
	)
	(footprint ""
		(layer "F.Cu")
		(at 145.422366 -128.683258 -90)
		(property "Reference" "C554"
			(at 0 0 270)
			(layer "F.SilkS")
			(hide yes)
			(effects
				(font
					(size 1.27 1.27)
				)
			)
		)
		(property "Value" "SCD033U50V3KX-1GP"
			(at 0 -2.8194 270)
			(unlocked yes)
			(layer "F.Fab")
			(hide yes)
			(effects
				(font
					(size 1.016 1.016)
					(thickness 0.1524)
				)
			)
		)
		(property "Device Type" "C603H36"
			(at 0 -4.3434 270)
			(unlocked yes)
			(layer "F.Fab")
			(hide yes)
			(effects
				(font
					(size 1.016 1.016)
					(thickness 0.1524)
				)
			)
		)
		(duplicate_pad_numbers_are_jumpers no)
		(fp_line
			(start 0.508 0)
			(end -0.508 0)
			(stroke
				(width 0.2032)
				(type default)
			)
			(layer "F.SilkS")
		)
		(fp_rect
			(start -0.5842 1.3335)
			(end 0.5842 -1.3335)
			(stroke
				(width 0)
				(type default)
			)
			(fill no)
			(layer "F.CrtYd")
		)
		(fp_rect
			(start -0.5842 1.3335)
			(end 0.5842 -1.3335)
			(stroke
				(width 0)
				(type default)
			)
			(fill no)
			(layer "F.Fab")
		)
		(pad "1" smd custom
			(at 0 -0.762 270)
			(size 0.2159 0.2159)
			(layers "F.Cu" "F.Mask" "F.Paste")
			(net "MB0_CM_GATE_C")
			(options
				(clearance outline)
				(anchor circle)
			)
			(primitives
				(gr_poly
					(pts
						(arc
							(start -0.3302 -0.4318)
							(mid -0.402042 -0.402042)
							(end -0.4318 -0.3302)
						)
						(arc
							(start -0.4318 0.3302)
							(mid -0.402042 0.402042)
							(end -0.3302 0.4318)
						)
						(arc
							(start 0.3302 0.4318)
							(mid 0.402042 0.402042)
							(end 0.4318 0.3302)
						)
						(arc
							(start 0.4318 -0.3302)
							(mid 0.402042 -0.402042)
							(end 0.3302 -0.4318)
						)
					)
					(width 0)
					(fill yes)
				)
			)
		)
		(pad "2" smd custom
			(at 0 0.762 270)
			(size 0.2159 0.2159)
			(layers "F.Cu" "F.Mask" "F.Paste")
			(net "GND")
			(options
				(clearance outline)
				(anchor circle)
			)
			(primitives
				(gr_poly
					(pts
						(arc
							(start -0.3302 -0.4318)
							(mid -0.402042 -0.402042)
							(end -0.4318 -0.3302)
						)
						(arc
							(start -0.4318 0.3302)
							(mid -0.402042 0.402042)
							(end -0.3302 0.4318)
						)
						(arc
							(start 0.3302 0.4318)
							(mid 0.402042 0.402042)
							(end 0.4318 0.3302)
						)
						(arc
							(start 0.4318 -0.3302)
							(mid 0.402042 -0.402042)
							(end 0.3302 -0.4318)
						)
					)
					(width 0)
					(fill yes)
				)
			)
		)
	)
	(footprint ""
		(layer "F.Cu")
		(at 452.288402 -258.47675 -90)
		(property "Reference" "R1244"
			(at 0 0 270)
			(layer "F.SilkS")
			(hide yes)
			(effects
				(font
					(size 1.27 1.27)
				)
			)
		)
		(property "Value" "0R2J-2-GP"
			(at 0.064008 -3.993896 270)
			(unlocked yes)
			(layer "F.Fab")
			(hide yes)
			(effects
				(font
					(size 1.016 1.016)
					(thickness 0.1524)
				)
			)
		)
		(property "Device Type" "R402H16"
			(at 0.064008 -5.517896 270)
			(unlocked yes)
			(layer "F.Fab")
			(hide yes)
			(effects
				(font
					(size 1.016 1.016)
					(thickness 0.1524)
				)
			)
		)
		(duplicate_pad_numbers_are_jumpers no)
		(fp_line
			(start -0.508 -0.9398)
			(end -0.508 0.9398)
			(stroke
				(width 0.1524)
				(type default)
			)
			(layer "F.SilkS")
		)
		(fp_line
			(start 0.508 -0.9398)
			(end -0.508 -0.9398)
			(stroke
				(width 0.1524)
				(type default)
			)
			(layer "F.SilkS")
		)
		(fp_rect
			(start -0.508 0.9398)
			(end 0.508 -0.9398)
			(stroke
				(width 0)
				(type default)
			)
			(fill no)
			(layer "F.CrtYd")
		)
		(fp_rect
			(start -0.508 0.9398)
			(end 0.508 -0.9398)
			(stroke
				(width 0)
				(type default)
			)
			(fill no)
			(layer "F.Fab")
		)
		(pad "1" smd custom
			(at 0 -0.4445 270)
			(size 0.1397 0.1397)
			(layers "F.Cu" "F.Mask" "F.Paste")
			(net "P12V_A_PGOOD")
			(options
				(clearance outline)
				(anchor circle)
			)
			(primitives
				(gr_poly
					(pts
						(arc
							(start -0.1778 -0.2794)
							(mid -0.249642 -0.249642)
							(end -0.2794 -0.1778)
						)
						(arc
							(start -0.2794 0.1778)
							(mid -0.249642 0.249642)
							(end -0.1778 0.2794)
						)
						(arc
							(start 0.1778 0.2794)
							(mid 0.249642 0.249642)
							(end 0.2794 0.1778)
						)
						(arc
							(start 0.2794 -0.1778)
							(mid 0.249642 -0.249642)
							(end 0.1778 -0.2794)
						)
					)
					(width 0)
					(fill yes)
				)
			)
		)
		(pad "2" smd custom
			(at 0 0.4445 270)
			(size 0.1397 0.1397)
			(layers "F.Cu" "F.Mask" "F.Paste")
			(net "P5V_C_EN_R")
			(options
				(clearance outline)
				(anchor circle)
			)
			(primitives
				(gr_poly
					(pts
						(arc
							(start -0.1778 -0.2794)
							(mid -0.249642 -0.249642)
							(end -0.2794 -0.1778)
						)
						(arc
							(start -0.2794 0.1778)
							(mid -0.249642 0.249642)
							(end -0.1778 0.2794)
						)
						(arc
							(start 0.1778 0.2794)
							(mid 0.249642 0.249642)
							(end 0.2794 0.1778)
						)
						(arc
							(start 0.2794 -0.1778)
							(mid 0.249642 -0.249642)
							(end 0.1778 -0.2794)
						)
					)
					(width 0)
					(fill yes)
				)
			)
		)
	)
)
